FILE_TYPE = CONNECTIVITY;
{Allegro Design Entry HDL 17.2-2016 S081 (4005846) 1/11/2022}
"PAGE_NUMBER" = 14;
0"NC";
1"M_E_CPU0_SA_DQ<31:0>";
2"M_E_CPU0_SB_DQ<31:0>";
3"M_E_CPU0_SA_CB<7:0>";
4"M_E_CPU0_SB_CB<7:0>";
5"M_E_CPU0_SA_DQS_DP<9:0>";
6"M_E_CPU0_SB_DQS_DP<9:0>";
7"M_E_CPU0_SA_CA<6:0>";
8"M_E_CPU0_SB_CA<6:0>";
9"M_E_CPU0_SA_DQS_DN<9:0>";
10"M_E_CPU0_SB_DQS_DN<9:0>";
11"M_E_CPU0_ALERT_N";
12"TP_M_E_CPU0_SA_TEST39E";
13"M_E_CPU0_ALERT_R_N";
14"M_E_CPU0_SA_CS_N<1>";
15"M_E_CPU0_SA_CS_N<0>";
16"M_E_CPU0_CLK_DN<0>";
17"M_E_CPU0_CLK_DP<0>";
18"M_E_CPU0_RESET_N";
19"M_E_CPU0_SB_PAR";
20"M_E_CPU0_SB_CS_N<1>";
21"M_E_CPU0_SB_CS_N<0>";
22"M_E_CPU0_SA_PAR";
23"M_E_CPU0_SA_RSP<0>";
24"M_E_CPU0_SB_RSP<0>";
25"M_E_CPU0_SB_CA<6>";
26"M_E_CPU0_SA_CA<6>";
27"M_E_CPU0_SB_CA<5>";
28"M_E_CPU0_SA_CA<5>";
29"M_E_CPU0_SB_CA<4>";
30"M_E_CPU0_SA_CA<4>";
31"M_E_CPU0_SB_CA<3>";
32"M_E_CPU0_SA_CA<3>";
33"M_E_CPU0_SB_CA<2>";
34"M_E_CPU0_SA_CA<2>";
35"M_E_CPU0_SB_CA<1>";
36"M_E_CPU0_SB_DQS_DN<9>";
37"M_E_CPU0_SA_CA<1>";
38"M_E_CPU0_SB_CA<0>";
39"M_E_CPU0_SA_CA<0>";
40"M_E_CPU0_SB_DQS_DP<9>";
41"M_E_CPU0_SB_DQS_DN<1>";
42"M_E_CPU0_SB_DQS_DN<0>";
43"M_E_CPU0_SB_DQS_DP<8>";
44"M_E_CPU0_SB_DQS_DP<7>";
45"M_E_CPU0_SB_DQS_DP<6>";
46"M_E_CPU0_SB_DQS_DP<5>";
47"M_E_CPU0_SB_DQS_DP<4>";
48"M_E_CPU0_SB_DQS_DN<8>";
49"M_E_CPU0_SB_DQS_DP<3>";
50"M_E_CPU0_SB_DQS_DN<7>";
51"M_E_CPU0_SB_DQS_DP<2>";
52"M_E_CPU0_SB_DQS_DN<6>";
53"M_E_CPU0_SB_DQS_DP<1>";
54"M_E_CPU0_SB_DQS_DN<5>";
55"M_E_CPU0_SB_DQS_DP<0>";
56"M_E_CPU0_SB_DQS_DN<4>";
57"M_E_CPU0_SA_DQS_DN<9>";
58"M_E_CPU0_SB_DQS_DN<3>";
59"M_E_CPU0_SB_DQS_DN<2>";
60"M_E_CPU0_SA_DQS_DP<3>";
61"M_E_CPU0_SA_DQS_DN<7>";
62"M_E_CPU0_SA_DQS_DP<2>";
63"M_E_CPU0_SA_DQS_DN<6>";
64"M_E_CPU0_SA_DQS_DP<1>";
65"M_E_CPU0_SA_DQS_DN<5>";
66"M_E_CPU0_SA_DQS_DP<0>";
67"M_E_CPU0_SA_DQS_DN<4>";
68"M_E_CPU0_SA_DQS_DN<3>";
69"M_E_CPU0_SA_DQS_DN<2>";
70"M_E_CPU0_SA_DQS_DN<1>";
71"M_E_CPU0_SA_DQS_DN<0>";
72"M_E_CPU0_SA_DQS_DP<9>";
73"M_E_CPU0_SA_DQS_DP<8>";
74"M_E_CPU0_SA_DQS_DP<7>";
75"M_E_CPU0_SA_DQS_DP<6>";
76"M_E_CPU0_SA_DQS_DP<5>";
77"M_E_CPU0_SA_DQS_DP<4>";
78"M_E_CPU0_SA_DQS_DN<8>";
79"M_E_CPU0_SB_CB<5>";
80"M_E_CPU0_SB_CB<4>";
81"M_E_CPU0_SB_CB<3>";
82"M_E_CPU0_SB_CB<2>";
83"M_E_CPU0_SB_CB<1>";
84"M_E_CPU0_SB_CB<0>";
85"M_E_CPU0_SB_CB<7>";
86"M_E_CPU0_SB_CB<6>";
87"M_E_CPU0_SB_DQ<25>";
88"M_E_CPU0_SB_DQ<24>";
89"M_E_CPU0_SB_DQ<23>";
90"M_E_CPU0_SB_DQ<22>";
91"M_E_CPU0_SA_CB<7>";
92"M_E_CPU0_SA_CB<6>";
93"M_E_CPU0_SB_DQ<31>";
94"M_E_CPU0_SA_CB<5>";
95"M_E_CPU0_SB_DQ<30>";
96"M_E_CPU0_SA_CB<4>";
97"M_E_CPU0_SA_CB<3>";
98"M_E_CPU0_SA_CB<2>";
99"M_E_CPU0_SA_CB<1>";
100"M_E_CPU0_SA_CB<0>";
101"M_E_CPU0_SB_DQ<29>";
102"M_E_CPU0_SB_DQ<28>";
103"M_E_CPU0_SB_DQ<27>";
104"M_E_CPU0_SB_DQ<26>";
105"M_E_CPU0_SB_DQ<14>";
106"M_E_CPU0_SB_DQ<13>";
107"M_E_CPU0_SB_DQ<12>";
108"M_E_CPU0_SB_DQ<9>";
109"M_E_CPU0_SB_DQ<11>";
110"M_E_CPU0_SB_DQ<8>";
111"M_E_CPU0_SB_DQ<10>";
112"M_E_CPU0_SB_DQ<21>";
113"M_E_CPU0_SB_DQ<7>";
114"M_E_CPU0_SB_DQ<20>";
115"M_E_CPU0_SB_DQ<6>";
116"M_E_CPU0_SB_DQ<5>";
117"M_E_CPU0_SB_DQ<4>";
118"M_E_CPU0_SB_DQ<19>";
119"M_E_CPU0_SB_DQ<18>";
120"M_E_CPU0_SB_DQ<17>";
121"M_E_CPU0_SB_DQ<16>";
122"M_E_CPU0_SB_DQ<15>";
123"M_E_CPU0_SA_DQ<19>";
124"M_E_CPU0_SA_DQ<18>";
125"M_E_CPU0_SA_DQ<29>";
126"M_E_CPU0_SA_DQ<17>";
127"M_E_CPU0_SA_DQ<28>";
128"M_E_CPU0_SA_DQ<27>";
129"M_E_CPU0_SA_DQ<26>";
130"M_E_CPU0_SA_DQ<25>";
131"M_E_CPU0_SA_DQ<24>";
132"M_E_CPU0_SA_DQ<23>";
133"M_E_CPU0_SA_DQ<22>";
134"M_E_CPU0_SB_DQ<3>";
135"M_E_CPU0_SA_DQ<21>";
136"M_E_CPU0_SB_DQ<2>";
137"M_E_CPU0_SA_DQ<20>";
138"M_E_CPU0_SA_DQ<31>";
139"M_E_CPU0_SB_DQ<1>";
140"M_E_CPU0_SA_DQ<30>";
141"M_E_CPU0_SB_DQ<0>";
142"M_E_CPU0_SA_DQ<9>";
143"M_E_CPU0_SA_DQ<16>";
144"M_E_CPU0_SA_DQ<8>";
145"M_E_CPU0_SA_DQ<15>";
146"M_E_CPU0_SA_DQ<7>";
147"M_E_CPU0_SA_DQ<14>";
148"M_E_CPU0_SA_DQ<6>";
149"M_E_CPU0_SA_DQ<13>";
150"M_E_CPU0_SA_DQ<5>";
151"M_E_CPU0_SA_DQ<12>";
152"M_E_CPU0_SA_DQ<4>";
153"M_E_CPU0_SA_DQ<11>";
154"M_E_CPU0_SA_DQ<3>";
155"M_E_CPU0_SA_DQ<10>";
156"M_E_CPU0_SA_DQ<2>";
157"M_E_CPU0_SA_DQ<1>";
158"M_E_CPU0_SA_DQ<0>";
%"GENOA_SP5"
"5","(-4675,3675)","0","pure_quanta","I159";
;
LOCATION"U25"
$SEC"5"
CDS_SEC"5"
PART_TYPE"SMLF"
MATERIAL"IO"
VALUE"SOCKET6096_13568-001"
PART_NUMBER"DGA^6000030"
CDS_LIB"pure_quanta"
CDS_LMAN_SYM_OUTLINE"-650,2525,650,-2525"
NEEDS_NO_SIZE"TRUE";
"TEST39E"
$PN"BF69"12;
"ME1_CLK_L"
$PN"BG71"0;
"ME1_CLK_H"
$PN"BF70"0;
"ME0_CLK_L"
$PN"BD70"16;
"ME0_CLK_H"
$PN"BC71"17;
"MEB_DQS_H9"
$PN"BV70"40;
"MEB_PAR"
$PN"BL71"19;
"MEA_PAR"
$PN"BC69"22;
"MEA_DQS_H3"
$PN"AE71"60;
"MEA_DQS_L7"
$PN"Y69"61;
"MEB_CHECK5"
$PN"BU69"79;
"MEB_DATA14"
$PN"CN71"105;
"MEB_DATA25"
$PN"DA69"87;
"MEB_DQS_L1"
$PN"CL71"41;
"MEA_DATA19"
$PN"W69"123;
"MEA_DQS_H2"
$PN"W71"62;
"MEA_DQS_L6"
$PN"P69"63;
"MEB_CHECK4"
$PN"BT70"80;
"MEB_DATA13"
$PN"CN69"106;
"MEB_DATA24"
$PN"CY70"88;
"MEB_DQS_L0"
$PN"CE71"42;
"MEA_DATA18"
$PN"V70"124;
"MEA_DATA29"
$PN"AH69"125;
"MEA_DQS_H1"
$PN"N71"64;
"MEA_DQS_L5"
$PN"H69"65;
"MEB_CHECK3"
$PN"CB69"81;
"MEB_DATA12"
$PN"CM70"107;
"MEB_DATA23"
$PN"CY69"89;
"MEA_DATA17"
$PN"V69"126;
"MEA_DATA28"
$PN"AG71"127;
"MEA_DQS_H0"
$PN"G71"66;
"MEA_DQS_L4"
$PN"AM70"67;
"MEB_CHECK2"
$PN"CA71"82;
"MEB_DATA9"
$PN"CJ69"108;
"MEB_DATA11"
$PN"CK69"109;
"MEB_DATA22"
$PN"CW71"90;
"MEA0_RSP_L"
$PN"BN69"23;
"MEA1_RSP_L"
$PN"BP69"0;
"MEA_CHECK7"
$PN"AR69"91;
"MEA_DATA9"
$PN"M69"142;
"MEA_DATA16"
$PN"U71"143;
"MEA_DATA27"
$PN"AE69"128;
"MEA_DQS_L3"
$PN"AF70"68;
"MEB_CA6"
$PN"BK70"25;
"MEB_CHECK1"
$PN"CA69"83;
"MEB_DATA8"
$PN"CH70"110;
"MEB_DATA10"
$PN"CJ71"111;
"MEB_DATA21"
$PN"CW69"112;
"MEA_CA6"
$PN"BB69"26;
"MEA_CHECK6"
$PN"AP70"92;
"MEA_DATA8"
$PN"L71"144;
"MEA_DATA15"
$PN"U69"145;
"MEA_DATA26"
$PN"AD70"129;
"MEA_DQS_L2"
$PN"Y70"69;
"MEB_CA5"
$PN"BK69"27;
"MEB_CHECK0"
$PN"BY70"84;
"MEB_DATA7"
$PN"CH69"113;
"MEB_DATA20"
$PN"CV70"114;
"MEB_DATA31"
$PN"DF69"93;
"MEA_CA5"
$PN"BB70"28;
"MEA_CHECK5"
$PN"AP69"94;
"MEA_DATA7"
$PN"L69"146;
"MEA_DATA14"
$PN"T70"147;
"MEA_DATA25"
$PN"AD69"130;
"MEA_DQS_L1"
$PN"P70"70;
"MEB0_CS_L1"
$PN"BN71"20;
"MEB1_CS_L1"
$PN"BM70"0;
"MEB_CA4"
$PN"BJ69"29;
"MEB_DATA6"
$PN"CG71"115;
"MEB_DATA30"
$PN"DE71"95;
"MEB_DQS_H8"
$PN"DD69"43;
"MEA_CA4"
$PN"BA71"30;
"MEA_CHECK4"
$PN"AN71"96;
"MEA_DATA6"
$PN"K70"148;
"MEA_DATA13"
$PN"T69"149;
"MEA_DATA24"
$PN"AC71"131;
"MEA_DQS_L0"
$PN"H70"71;
"MEB0_CS_L0"
$PN"BM69"21;
"MEB1_CS_L0"
$PN"BL69"0;
"MEB_CA3"
$PN"BJ71"31;
"MEB_DATA5"
$PN"CG69"116;
"MEB_DQS_H7"
$PN"CV69"44;
"MEA_CA3"
$PN"BA69"32;
"MEA_CHECK3"
$PN"AL69"97;
"MEA_DATA5"
$PN"K69"150;
"MEA_DATA12"
$PN"R71"151;
"MEA_DATA23"
$PN"AC69"132;
"MEB_CA2"
$PN"BH70"33;
"MEB_DATA4"
$PN"CF70"117;
"MEB_DQS_H6"
$PN"CM69"45;
"MEA_CA2"
$PN"AY69"34;
"MEA_CHECK2"
$PN"AK70"98;
"MEA_DATA4"
$PN"J71"152;
"MEA_DATA11"
$PN"N69"153;
"MEA_DATA22"
$PN"AB70"133;
"MEB_CA1"
$PN"BH69"35;
"MEB_DATA3"
$PN"CD69"134;
"MEB_DQS_H5"
$PN"CF69"46;
"MEB_DQS_L9"
$PN"BW71"36;
"MEA_CA1"
$PN"AY70"37;
"MEA_CHECK1"
$PN"AK69"99;
"MEA_DATA3"
$PN"G69"154;
"MEA_DATA10"
$PN"M70"155;
"MEA_DATA21"
$PN"AB69"135;
"MEB_CA0"
$PN"BG69"38;
"MEB_DATA2"
$PN"CC71"136;
"MEB_DQS_H4"
$PN"BY69"47;
"MEB_DQS_L8"
$PN"DC69"48;
"MEA_CA0"
$PN"AW71"39;
"MEA_CHECK0"
$PN"AJ71"100;
"MEA_DATA2"
$PN"F70"156;
"MEA_DATA20"
$PN"AA71"137;
"MEA_DATA31"
$PN"AJ69"138;
"MEA_DQS_H9"
$PN"AN69"72;
"MEB_DATA1"
$PN"CC69"139;
"MEB_DQS_H3"
$PN"DB70"49;
"MEB_DQS_L7"
$PN"CU69"50;
"MEA0_CS_L1"
$PN"AW69"14;
"MEA1_CS_L1"
$PN"AV69"0;
"MEA_DATA1"
$PN"F69"157;
"MEA_DATA30"
$PN"AH70"140;
"MEA_DQS_H8"
$PN"AG69"73;
"MEB_DATA0"
$PN"CB70"141;
"MEB_DATA19"
$PN"CT69"118;
"MEB_DQS_H2"
$PN"CT70"51;
"MEB_DQS_L6"
$PN"CL69"52;
"MEA0_CS_L0"
$PN"AV70"15;
"MEA1_CS_L0"
$PN"AU71"0;
"MEA_DATA0"
$PN"E71"158;
"MEA_DQS_H7"
$PN"AA69"74;
"MEB_DATA18"
$PN"CR71"119;
"MEB_DATA29"
$PN"DE69"101;
"MEB_DQS_H1"
$PN"CK70"53;
"MEB_DQS_L5"
$PN"CE69"54;
"MEA_DQS_H6"
$PN"R69"75;
"MEB_DATA17"
$PN"CR69"120;
"MEB_DATA28"
$PN"DD70"102;
"MEB_DQS_H0"
$PN"CD70"55;
"MEB_DQS_L4"
$PN"BW69"56;
"MEA_DQS_H5"
$PN"J69"76;
"MEA_DQS_L9"
$PN"AM69"57;
"MEB0_RSP_L"
$PN"BP70"24;
"MEB1_RSP_L"
$PN"BR71"0;
"MEB_CHECK7"
$PN"BV69"85;
"MEB_DATA16"
$PN"CP70"121;
"MEB_DATA27"
$PN"DB69"103;
"MEB_DQS_L3"
$PN"DC71"58;
"MEA_DQS_H4"
$PN"AL71"77;
"MEA_DQS_L8"
$PN"AF69"78;
"MEB_CHECK6"
$PN"BU71"86;
"MEB_DATA15"
$PN"CP69"122;
"MEB_DATA26"
$PN"DA71"104;
"MEB_DQS_L2"
$PN"CU71"59;
"ME_RESET_L"
$PN"AU69"18;
"ME_ALERT_L"
$PN"AT69"13;
%"TAP"
"1","(-3400,6050)","0","mstr_standard","I162";
;
CDS_LIB"mstr_standard"
BODY_TYPE"PLUMBING"
HDL_TAP"TRUE";
"B \NAC \NWC"1;
"S \NAC"
BN"0"158;
%"TAP"
"1","(-3400,5900)","0","mstr_standard","I163";
;
CDS_LIB"mstr_standard"
BODY_TYPE"PLUMBING"
HDL_TAP"TRUE";
"B \NAC \NWC"1;
"S \NAC"
BN"3"154;
%"TAP"
"1","(-3400,6000)","0","mstr_standard","I164";
;
CDS_LIB"mstr_standard"
BODY_TYPE"PLUMBING"
HDL_TAP"TRUE";
"B \NAC \NWC"1;
"S \NAC"
BN"1"157;
%"TAP"
"1","(-3400,5950)","0","mstr_standard","I165";
;
CDS_LIB"mstr_standard"
BODY_TYPE"PLUMBING"
HDL_TAP"TRUE";
"B \NAC \NWC"1;
"S \NAC"
BN"2"156;
%"TAP"
"1","(-3400,5800)","0","mstr_standard","I166";
;
CDS_LIB"mstr_standard"
BODY_TYPE"PLUMBING"
HDL_TAP"TRUE";
"B \NAC \NWC"1;
"S \NAC"
BN"5"150;
%"TAP"
"1","(-3400,5850)","0","mstr_standard","I167";
;
CDS_LIB"mstr_standard"
BODY_TYPE"PLUMBING"
HDL_TAP"TRUE";
"B \NAC \NWC"1;
"S \NAC"
BN"4"152;
%"TAP"
"1","(-3400,5750)","0","mstr_standard","I168";
;
CDS_LIB"mstr_standard"
BODY_TYPE"PLUMBING"
HDL_TAP"TRUE";
"B \NAC \NWC"1;
"S \NAC"
BN"6"148;
%"TAP"
"1","(-3400,5700)","0","mstr_standard","I169";
;
CDS_LIB"mstr_standard"
BODY_TYPE"PLUMBING"
HDL_TAP"TRUE";
"B \NAC \NWC"1;
"S \NAC"
BN"7"146;
%"TAP"
"1","(-3400,5550)","0","mstr_standard","I170";
;
CDS_LIB"mstr_standard"
BODY_TYPE"PLUMBING"
HDL_TAP"TRUE";
"B \NAC \NWC"1;
"S \NAC"
BN"9"142;
%"TAP"
"1","(-3400,5600)","0","mstr_standard","I171";
;
CDS_LIB"mstr_standard"
BODY_TYPE"PLUMBING"
HDL_TAP"TRUE";
"B \NAC \NWC"1;
"S \NAC"
BN"8"144;
%"TAP"
"1","(-3400,5400)","0","mstr_standard","I172";
;
CDS_LIB"mstr_standard"
BODY_TYPE"PLUMBING"
HDL_TAP"TRUE";
"B \NAC \NWC"1;
"S \NAC"
BN"12"151;
%"TAP"
"1","(-3400,5450)","0","mstr_standard","I173";
;
CDS_LIB"mstr_standard"
BODY_TYPE"PLUMBING"
HDL_TAP"TRUE";
"B \NAC \NWC"1;
"S \NAC"
BN"11"153;
%"TAP"
"1","(-3400,5500)","0","mstr_standard","I174";
;
CDS_LIB"mstr_standard"
BODY_TYPE"PLUMBING"
HDL_TAP"TRUE";
"B \NAC \NWC"1;
"S \NAC"
BN"10"155;
%"TAP"
"1","(-3400,5250)","0","mstr_standard","I175";
;
CDS_LIB"mstr_standard"
BODY_TYPE"PLUMBING"
HDL_TAP"TRUE";
"B \NAC \NWC"1;
"S \NAC"
BN"15"145;
%"TAP"
"1","(-3400,5300)","0","mstr_standard","I176";
;
CDS_LIB"mstr_standard"
BODY_TYPE"PLUMBING"
HDL_TAP"TRUE";
"B \NAC \NWC"1;
"S \NAC"
BN"14"147;
%"TAP"
"1","(-3400,5350)","0","mstr_standard","I177";
;
CDS_LIB"mstr_standard"
BODY_TYPE"PLUMBING"
HDL_TAP"TRUE";
"B \NAC \NWC"1;
"S \NAC"
BN"13"149;
%"TAP"
"1","(-3400,5150)","0","mstr_standard","I178";
;
CDS_LIB"mstr_standard"
BODY_TYPE"PLUMBING"
HDL_TAP"TRUE";
"B \NAC \NWC"1;
"S \NAC"
BN"16"143;
%"TAP"
"1","(-3400,5050)","0","mstr_standard","I179";
;
CDS_LIB"mstr_standard"
BODY_TYPE"PLUMBING"
HDL_TAP"TRUE";
"B \NAC \NWC"1;
"S \NAC"
BN"18"124;
%"TAP"
"1","(-3400,5100)","0","mstr_standard","I180";
;
CDS_LIB"mstr_standard"
BODY_TYPE"PLUMBING"
HDL_TAP"TRUE";
"B \NAC \NWC"1;
"S \NAC"
BN"17"126;
%"TAP"
"1","(-3400,5000)","0","mstr_standard","I181";
;
CDS_LIB"mstr_standard"
BODY_TYPE"PLUMBING"
HDL_TAP"TRUE";
"B \NAC \NWC"1;
"S \NAC"
BN"19"123;
%"TAP"
"1","(-3400,4950)","0","mstr_standard","I182";
;
CDS_LIB"mstr_standard"
BODY_TYPE"PLUMBING"
HDL_TAP"TRUE";
"B \NAC \NWC"1;
"S \NAC"
BN"20"137;
%"TAP"
"1","(-3400,4900)","0","mstr_standard","I183";
;
CDS_LIB"mstr_standard"
BODY_TYPE"PLUMBING"
HDL_TAP"TRUE";
"B \NAC \NWC"1;
"S \NAC"
BN"21"135;
%"TAP"
"1","(-3400,4800)","0","mstr_standard","I184";
;
CDS_LIB"mstr_standard"
BODY_TYPE"PLUMBING"
HDL_TAP"TRUE";
"B \NAC \NWC"1;
"S \NAC"
BN"23"132;
%"TAP"
"1","(-3400,4850)","0","mstr_standard","I185";
;
CDS_LIB"mstr_standard"
BODY_TYPE"PLUMBING"
HDL_TAP"TRUE";
"B \NAC \NWC"1;
"S \NAC"
BN"22"133;
%"TAP"
"1","(-3400,4650)","0","mstr_standard","I186";
;
CDS_LIB"mstr_standard"
BODY_TYPE"PLUMBING"
HDL_TAP"TRUE";
"B \NAC \NWC"1;
"S \NAC"
BN"25"130;
%"TAP"
"1","(-3400,4700)","0","mstr_standard","I187";
;
CDS_LIB"mstr_standard"
BODY_TYPE"PLUMBING"
HDL_TAP"TRUE";
"B \NAC \NWC"1;
"S \NAC"
BN"24"131;
%"TAP"
"1","(-3400,4600)","0","mstr_standard","I188";
;
CDS_LIB"mstr_standard"
BODY_TYPE"PLUMBING"
HDL_TAP"TRUE";
"B \NAC \NWC"1;
"S \NAC"
BN"26"129;
%"TAP"
"1","(-3400,4550)","0","mstr_standard","I189";
;
CDS_LIB"mstr_standard"
BODY_TYPE"PLUMBING"
HDL_TAP"TRUE";
"B \NAC \NWC"1;
"S \NAC"
BN"27"128;
%"TAP"
"1","(-3400,4500)","0","mstr_standard","I190";
;
CDS_LIB"mstr_standard"
BODY_TYPE"PLUMBING"
HDL_TAP"TRUE";
"B \NAC \NWC"1;
"S \NAC"
BN"28"127;
%"TAP"
"1","(-3400,4450)","0","mstr_standard","I191";
;
CDS_LIB"mstr_standard"
BODY_TYPE"PLUMBING"
HDL_TAP"TRUE";
"B \NAC \NWC"1;
"S \NAC"
BN"29"125;
%"TAP"
"1","(-3400,4400)","0","mstr_standard","I192";
;
CDS_LIB"mstr_standard"
BODY_TYPE"PLUMBING"
HDL_TAP"TRUE";
"B \NAC \NWC"1;
"S \NAC"
BN"30"140;
%"TAP"
"1","(-3400,4350)","0","mstr_standard","I193";
;
CDS_LIB"mstr_standard"
BODY_TYPE"PLUMBING"
HDL_TAP"TRUE";
"B \NAC \NWC"1;
"S \NAC"
BN"31"138;
%"TAP"
"1","(-3400,4250)","0","mstr_standard","I194";
;
CDS_LIB"mstr_standard"
BODY_TYPE"PLUMBING"
HDL_TAP"TRUE";
"B \NAC \NWC"2;
"S \NAC"
BN"0"141;
%"TAP"
"1","(-3400,4100)","0","mstr_standard","I195";
;
CDS_LIB"mstr_standard"
BODY_TYPE"PLUMBING"
HDL_TAP"TRUE";
"B \NAC \NWC"2;
"S \NAC"
BN"3"134;
%"TAP"
"1","(-3400,4200)","0","mstr_standard","I196";
;
CDS_LIB"mstr_standard"
BODY_TYPE"PLUMBING"
HDL_TAP"TRUE";
"B \NAC \NWC"2;
"S \NAC"
BN"1"139;
%"TAP"
"1","(-3400,4150)","0","mstr_standard","I197";
;
CDS_LIB"mstr_standard"
BODY_TYPE"PLUMBING"
HDL_TAP"TRUE";
"B \NAC \NWC"2;
"S \NAC"
BN"2"136;
%"TAP"
"1","(-3400,4000)","0","mstr_standard","I199";
;
CDS_LIB"mstr_standard"
BODY_TYPE"PLUMBING"
HDL_TAP"TRUE";
"B \NAC \NWC"2;
"S \NAC"
BN"5"116;
%"TAP"
"1","(-3400,4050)","0","mstr_standard","I200";
;
CDS_LIB"mstr_standard"
BODY_TYPE"PLUMBING"
HDL_TAP"TRUE";
"B \NAC \NWC"2;
"S \NAC"
BN"4"117;
%"TAP"
"1","(-3400,3950)","0","mstr_standard","I201";
;
CDS_LIB"mstr_standard"
BODY_TYPE"PLUMBING"
HDL_TAP"TRUE";
"B \NAC \NWC"2;
"S \NAC"
BN"6"115;
%"TAP"
"1","(-3400,3900)","0","mstr_standard","I202";
;
CDS_LIB"mstr_standard"
BODY_TYPE"PLUMBING"
HDL_TAP"TRUE";
"B \NAC \NWC"2;
"S \NAC"
BN"7"113;
%"TAP"
"1","(-3400,3800)","0","mstr_standard","I203";
;
CDS_LIB"mstr_standard"
BODY_TYPE"PLUMBING"
HDL_TAP"TRUE";
"B \NAC \NWC"2;
"S \NAC"
BN"8"110;
%"TAP"
"1","(-3400,3750)","0","mstr_standard","I204";
;
CDS_LIB"mstr_standard"
BODY_TYPE"PLUMBING"
HDL_TAP"TRUE";
"B \NAC \NWC"2;
"S \NAC"
BN"9"108;
%"TAP"
"1","(-3400,3600)","0","mstr_standard","I205";
;
CDS_LIB"mstr_standard"
BODY_TYPE"PLUMBING"
HDL_TAP"TRUE";
"B \NAC \NWC"2;
"S \NAC"
BN"12"107;
%"TAP"
"1","(-3400,3650)","0","mstr_standard","I206";
;
CDS_LIB"mstr_standard"
BODY_TYPE"PLUMBING"
HDL_TAP"TRUE";
"B \NAC \NWC"2;
"S \NAC"
BN"11"109;
%"TAP"
"1","(-3400,3700)","0","mstr_standard","I207";
;
CDS_LIB"mstr_standard"
BODY_TYPE"PLUMBING"
HDL_TAP"TRUE";
"B \NAC \NWC"2;
"S \NAC"
BN"10"111;
%"TAP"
"1","(-3400,3500)","0","mstr_standard","I208";
;
CDS_LIB"mstr_standard"
BODY_TYPE"PLUMBING"
HDL_TAP"TRUE";
"B \NAC \NWC"2;
"S \NAC"
BN"14"105;
%"TAP"
"1","(-3400,3550)","0","mstr_standard","I209";
;
CDS_LIB"mstr_standard"
BODY_TYPE"PLUMBING"
HDL_TAP"TRUE";
"B \NAC \NWC"2;
"S \NAC"
BN"13"106;
%"TAP"
"1","(-3400,3450)","0","mstr_standard","I210";
;
CDS_LIB"mstr_standard"
BODY_TYPE"PLUMBING"
HDL_TAP"TRUE";
"B \NAC \NWC"2;
"S \NAC"
BN"15"122;
%"TAP"
"1","(-3400,3350)","0","mstr_standard","I211";
;
CDS_LIB"mstr_standard"
BODY_TYPE"PLUMBING"
HDL_TAP"TRUE";
"B \NAC \NWC"2;
"S \NAC"
BN"16"121;
%"TAP"
"1","(-3400,3300)","0","mstr_standard","I212";
;
CDS_LIB"mstr_standard"
BODY_TYPE"PLUMBING"
HDL_TAP"TRUE";
"B \NAC \NWC"2;
"S \NAC"
BN"17"120;
%"TAP"
"1","(-3400,3250)","0","mstr_standard","I213";
;
CDS_LIB"mstr_standard"
BODY_TYPE"PLUMBING"
HDL_TAP"TRUE";
"B \NAC \NWC"2;
"S \NAC"
BN"18"119;
%"TAP"
"1","(-3400,3200)","0","mstr_standard","I214";
;
CDS_LIB"mstr_standard"
BODY_TYPE"PLUMBING"
HDL_TAP"TRUE";
"B \NAC \NWC"2;
"S \NAC"
BN"19"118;
%"TAP"
"1","(-3400,3150)","0","mstr_standard","I215";
;
CDS_LIB"mstr_standard"
BODY_TYPE"PLUMBING"
HDL_TAP"TRUE";
"B \NAC \NWC"2;
"S \NAC"
BN"20"114;
%"TAP"
"1","(-3400,3100)","0","mstr_standard","I216";
;
CDS_LIB"mstr_standard"
BODY_TYPE"PLUMBING"
HDL_TAP"TRUE";
"B \NAC \NWC"2;
"S \NAC"
BN"21"112;
%"TAP"
"1","(-3400,3000)","0","mstr_standard","I217";
;
CDS_LIB"mstr_standard"
BODY_TYPE"PLUMBING"
HDL_TAP"TRUE";
"B \NAC \NWC"2;
"S \NAC"
BN"23"89;
%"TAP"
"1","(-3400,3050)","0","mstr_standard","I218";
;
CDS_LIB"mstr_standard"
BODY_TYPE"PLUMBING"
HDL_TAP"TRUE";
"B \NAC \NWC"2;
"S \NAC"
BN"22"90;
%"TAP"
"1","(-3400,2900)","0","mstr_standard","I219";
;
CDS_LIB"mstr_standard"
BODY_TYPE"PLUMBING"
HDL_TAP"TRUE";
"B \NAC \NWC"2;
"S \NAC"
BN"24"88;
%"TAP"
"1","(-3400,2850)","0","mstr_standard","I220";
;
CDS_LIB"mstr_standard"
BODY_TYPE"PLUMBING"
HDL_TAP"TRUE";
"B \NAC \NWC"2;
"S \NAC"
BN"25"87;
%"TAP"
"1","(-3400,2800)","0","mstr_standard","I221";
;
CDS_LIB"mstr_standard"
BODY_TYPE"PLUMBING"
HDL_TAP"TRUE";
"B \NAC \NWC"2;
"S \NAC"
BN"26"104;
%"TAP"
"1","(-3400,2750)","0","mstr_standard","I222";
;
CDS_LIB"mstr_standard"
BODY_TYPE"PLUMBING"
HDL_TAP"TRUE";
"B \NAC \NWC"2;
"S \NAC"
BN"27"103;
%"TAP"
"1","(-3400,2700)","0","mstr_standard","I223";
;
CDS_LIB"mstr_standard"
BODY_TYPE"PLUMBING"
HDL_TAP"TRUE";
"B \NAC \NWC"2;
"S \NAC"
BN"28"102;
%"TAP"
"1","(-3400,2650)","0","mstr_standard","I224";
;
CDS_LIB"mstr_standard"
BODY_TYPE"PLUMBING"
HDL_TAP"TRUE";
"B \NAC \NWC"2;
"S \NAC"
BN"29"101;
%"TAP"
"1","(-3400,2600)","0","mstr_standard","I225";
;
CDS_LIB"mstr_standard"
BODY_TYPE"PLUMBING"
HDL_TAP"TRUE";
"B \NAC \NWC"2;
"S \NAC"
BN"30"95;
%"TAP"
"1","(-3400,2450)","0","mstr_standard","I226";
;
CDS_LIB"mstr_standard"
BODY_TYPE"PLUMBING"
HDL_TAP"TRUE";
"B \NAC \NWC"3;
"S \NAC"
BN"0"100;
%"TAP"
"1","(-3400,2550)","0","mstr_standard","I227";
;
CDS_LIB"mstr_standard"
BODY_TYPE"PLUMBING"
HDL_TAP"TRUE";
"B \NAC \NWC"2;
"S \NAC"
BN"31"93;
%"TAP"
"1","(-3400,2350)","0","mstr_standard","I228";
;
CDS_LIB"mstr_standard"
BODY_TYPE"PLUMBING"
HDL_TAP"TRUE";
"B \NAC \NWC"3;
"S \NAC"
BN"2"98;
%"TAP"
"1","(-3400,2400)","0","mstr_standard","I229";
;
CDS_LIB"mstr_standard"
BODY_TYPE"PLUMBING"
HDL_TAP"TRUE";
"B \NAC \NWC"3;
"S \NAC"
BN"1"99;
%"TAP"
"1","(-3400,2250)","0","mstr_standard","I230";
;
CDS_LIB"mstr_standard"
BODY_TYPE"PLUMBING"
HDL_TAP"TRUE";
"B \NAC \NWC"3;
"S \NAC"
BN"4"96;
%"TAP"
"1","(-3400,2300)","0","mstr_standard","I231";
;
CDS_LIB"mstr_standard"
BODY_TYPE"PLUMBING"
HDL_TAP"TRUE";
"B \NAC \NWC"3;
"S \NAC"
BN"3"97;
%"TAP"
"1","(-3400,2200)","0","mstr_standard","I232";
;
CDS_LIB"mstr_standard"
BODY_TYPE"PLUMBING"
HDL_TAP"TRUE";
"B \NAC \NWC"3;
"S \NAC"
BN"5"94;
%"TAP"
"1","(-3400,2150)","0","mstr_standard","I233";
;
CDS_LIB"mstr_standard"
BODY_TYPE"PLUMBING"
HDL_TAP"TRUE";
"B \NAC \NWC"3;
"S \NAC"
BN"6"92;
%"TAP"
"1","(-3400,2100)","0","mstr_standard","I234";
;
CDS_LIB"mstr_standard"
BODY_TYPE"PLUMBING"
HDL_TAP"TRUE";
"B \NAC \NWC"3;
"S \NAC"
BN"7"91;
%"TAP"
"1","(-3400,1950)","0","mstr_standard","I236";
;
CDS_LIB"mstr_standard"
BODY_TYPE"PLUMBING"
HDL_TAP"TRUE";
"B \NAC \NWC"4;
"S \NAC"
BN"1"83;
%"TAP"
"1","(-3400,2000)","0","mstr_standard","I237";
;
CDS_LIB"mstr_standard"
BODY_TYPE"PLUMBING"
HDL_TAP"TRUE";
"B \NAC \NWC"4;
"S \NAC"
BN"0"84;
%"TAP"
"1","(-3400,1800)","0","mstr_standard","I238";
;
CDS_LIB"mstr_standard"
BODY_TYPE"PLUMBING"
HDL_TAP"TRUE";
"B \NAC \NWC"4;
"S \NAC"
BN"4"80;
%"TAP"
"1","(-3400,1900)","0","mstr_standard","I239";
;
CDS_LIB"mstr_standard"
BODY_TYPE"PLUMBING"
HDL_TAP"TRUE";
"B \NAC \NWC"4;
"S \NAC"
BN"2"82;
%"TAP"
"1","(-3400,1850)","0","mstr_standard","I240";
;
CDS_LIB"mstr_standard"
BODY_TYPE"PLUMBING"
HDL_TAP"TRUE";
"B \NAC \NWC"4;
"S \NAC"
BN"3"81;
%"TAP"
"1","(-3400,1700)","0","mstr_standard","I241";
;
CDS_LIB"mstr_standard"
BODY_TYPE"PLUMBING"
HDL_TAP"TRUE";
"B \NAC \NWC"4;
"S \NAC"
BN"6"86;
%"TAP"
"1","(-3400,1750)","0","mstr_standard","I242";
;
CDS_LIB"mstr_standard"
BODY_TYPE"PLUMBING"
HDL_TAP"TRUE";
"B \NAC \NWC"4;
"S \NAC"
BN"5"79;
%"TAP"
"1","(-3400,1650)","0","mstr_standard","I243";
;
CDS_LIB"mstr_standard"
BODY_TYPE"PLUMBING"
HDL_TAP"TRUE";
"B \NAC \NWC"4;
"S \NAC"
BN"7"85;
%"TAP"
"1","(-5825,6050)","2","mstr_standard","I244";
;
CDS_LIB"mstr_standard"
BODY_TYPE"PLUMBING"
HDL_TAP"TRUE";
"B \NAC \NWC"5;
"S \NAC"
BN"0"66;
%"TAP"
"1","(-5825,5950)","2","mstr_standard","I245";
;
CDS_LIB"mstr_standard"
BODY_TYPE"PLUMBING"
HDL_TAP"TRUE";
"B \NAC \NWC"5;
"S \NAC"
BN"1"64;
%"TAP"
"1","(-5825,5750)","2","mstr_standard","I246";
;
CDS_LIB"mstr_standard"
BODY_TYPE"PLUMBING"
HDL_TAP"TRUE";
"B \NAC \NWC"5;
"S \NAC"
BN"3"60;
%"TAP"
"1","(-5825,5850)","2","mstr_standard","I247";
;
CDS_LIB"mstr_standard"
BODY_TYPE"PLUMBING"
HDL_TAP"TRUE";
"B \NAC \NWC"5;
"S \NAC"
BN"2"62;
%"TAP"
"1","(-5825,5650)","2","mstr_standard","I248";
;
CDS_LIB"mstr_standard"
BODY_TYPE"PLUMBING"
HDL_TAP"TRUE";
"B \NAC \NWC"5;
"S \NAC"
BN"4"77;
%"TAP"
"1","(-6025,6000)","2","mstr_standard","I249";
;
CDS_LIB"mstr_standard"
BODY_TYPE"PLUMBING"
HDL_TAP"TRUE";
"B \NAC \NWC"9;
"S \NAC"
BN"0"71;
%"TAP"
"1","(-6025,5900)","2","mstr_standard","I250";
;
CDS_LIB"mstr_standard"
BODY_TYPE"PLUMBING"
HDL_TAP"TRUE";
"B \NAC \NWC"9;
"S \NAC"
BN"1"70;
%"TAP"
"1","(-6025,5800)","2","mstr_standard","I251";
;
CDS_LIB"mstr_standard"
BODY_TYPE"PLUMBING"
HDL_TAP"TRUE";
"B \NAC \NWC"9;
"S \NAC"
BN"2"69;
%"TAP"
"1","(-6025,5700)","2","mstr_standard","I252";
;
CDS_LIB"mstr_standard"
BODY_TYPE"PLUMBING"
HDL_TAP"TRUE";
"B \NAC \NWC"9;
"S \NAC"
BN"3"68;
%"TAP"
"1","(-5825,5550)","2","mstr_standard","I253";
;
CDS_LIB"mstr_standard"
BODY_TYPE"PLUMBING"
HDL_TAP"TRUE";
"B \NAC \NWC"5;
"S \NAC"
BN"5"76;
%"TAP"
"1","(-5825,5450)","2","mstr_standard","I254";
;
CDS_LIB"mstr_standard"
BODY_TYPE"PLUMBING"
HDL_TAP"TRUE";
"B \NAC \NWC"5;
"S \NAC"
BN"6"75;
%"TAP"
"1","(-5825,5250)","2","mstr_standard","I255";
;
CDS_LIB"mstr_standard"
BODY_TYPE"PLUMBING"
HDL_TAP"TRUE";
"B \NAC \NWC"5;
"S \NAC"
BN"8"73;
%"TAP"
"1","(-5825,5350)","2","mstr_standard","I256";
;
CDS_LIB"mstr_standard"
BODY_TYPE"PLUMBING"
HDL_TAP"TRUE";
"B \NAC \NWC"5;
"S \NAC"
BN"7"74;
%"TAP"
"1","(-5825,5150)","2","mstr_standard","I257";
;
CDS_LIB"mstr_standard"
BODY_TYPE"PLUMBING"
HDL_TAP"TRUE";
"B \NAC \NWC"5;
"S \NAC"
BN"9"72;
%"TAP"
"1","(-6025,5600)","2","mstr_standard","I258";
;
CDS_LIB"mstr_standard"
BODY_TYPE"PLUMBING"
HDL_TAP"TRUE";
"B \NAC \NWC"9;
"S \NAC"
BN"4"67;
%"TAP"
"1","(-6025,5500)","2","mstr_standard","I259";
;
CDS_LIB"mstr_standard"
BODY_TYPE"PLUMBING"
HDL_TAP"TRUE";
"B \NAC \NWC"9;
"S \NAC"
BN"5"65;
%"TAP"
"1","(-6025,5400)","2","mstr_standard","I260";
;
CDS_LIB"mstr_standard"
BODY_TYPE"PLUMBING"
HDL_TAP"TRUE";
"B \NAC \NWC"9;
"S \NAC"
BN"6"63;
%"TAP"
"1","(-6025,5300)","2","mstr_standard","I261";
;
CDS_LIB"mstr_standard"
BODY_TYPE"PLUMBING"
HDL_TAP"TRUE";
"B \NAC \NWC"9;
"S \NAC"
BN"7"61;
%"TAP"
"1","(-6025,5200)","2","mstr_standard","I262";
;
CDS_LIB"mstr_standard"
BODY_TYPE"PLUMBING"
HDL_TAP"TRUE";
"B \NAC \NWC"9;
"S \NAC"
BN"8"78;
%"TAP"
"1","(-5825,4900)","2","mstr_standard","I263";
;
CDS_LIB"mstr_standard"
BODY_TYPE"PLUMBING"
HDL_TAP"TRUE";
"B \NAC \NWC"6;
"S \NAC"
BN"1"53;
%"TAP"
"1","(-5825,5000)","2","mstr_standard","I264";
;
CDS_LIB"mstr_standard"
BODY_TYPE"PLUMBING"
HDL_TAP"TRUE";
"B \NAC \NWC"6;
"S \NAC"
BN"0"55;
%"TAP"
"1","(-5825,4800)","2","mstr_standard","I265";
;
CDS_LIB"mstr_standard"
BODY_TYPE"PLUMBING"
HDL_TAP"TRUE";
"B \NAC \NWC"6;
"S \NAC"
BN"2"51;
%"TAP"
"1","(-5825,4700)","2","mstr_standard","I266";
;
CDS_LIB"mstr_standard"
BODY_TYPE"PLUMBING"
HDL_TAP"TRUE";
"B \NAC \NWC"6;
"S \NAC"
BN"3"49;
%"TAP"
"1","(-6025,4950)","2","mstr_standard","I267";
;
CDS_LIB"mstr_standard"
BODY_TYPE"PLUMBING"
HDL_TAP"TRUE";
"B \NAC \NWC"10;
"S \NAC"
BN"0"42;
%"TAP"
"1","(-6025,5100)","2","mstr_standard","I268";
;
CDS_LIB"mstr_standard"
BODY_TYPE"PLUMBING"
HDL_TAP"TRUE";
"B \NAC \NWC"9;
"S \NAC"
BN"9"57;
%"TAP"
"1","(-6025,4850)","2","mstr_standard","I269";
;
CDS_LIB"mstr_standard"
BODY_TYPE"PLUMBING"
HDL_TAP"TRUE";
"B \NAC \NWC"10;
"S \NAC"
BN"1"41;
%"TAP"
"1","(-6025,4750)","2","mstr_standard","I270";
;
CDS_LIB"mstr_standard"
BODY_TYPE"PLUMBING"
HDL_TAP"TRUE";
"B \NAC \NWC"10;
"S \NAC"
BN"2"59;
%"TAP"
"1","(-6025,4650)","2","mstr_standard","I271";
;
CDS_LIB"mstr_standard"
BODY_TYPE"PLUMBING"
HDL_TAP"TRUE";
"B \NAC \NWC"10;
"S \NAC"
BN"3"58;
%"TAP"
"1","(-5825,4600)","2","mstr_standard","I272";
;
CDS_LIB"mstr_standard"
BODY_TYPE"PLUMBING"
HDL_TAP"TRUE";
"B \NAC \NWC"6;
"S \NAC"
BN"4"47;
%"TAP"
"1","(-5825,4500)","2","mstr_standard","I273";
;
CDS_LIB"mstr_standard"
BODY_TYPE"PLUMBING"
HDL_TAP"TRUE";
"B \NAC \NWC"6;
"S \NAC"
BN"5"46;
%"TAP"
"1","(-5825,4400)","2","mstr_standard","I274";
;
CDS_LIB"mstr_standard"
BODY_TYPE"PLUMBING"
HDL_TAP"TRUE";
"B \NAC \NWC"6;
"S \NAC"
BN"6"45;
%"TAP"
"1","(-5825,4200)","2","mstr_standard","I275";
;
CDS_LIB"mstr_standard"
BODY_TYPE"PLUMBING"
HDL_TAP"TRUE";
"B \NAC \NWC"6;
"S \NAC"
BN"8"43;
%"TAP"
"1","(-5825,4300)","2","mstr_standard","I276";
;
CDS_LIB"mstr_standard"
BODY_TYPE"PLUMBING"
HDL_TAP"TRUE";
"B \NAC \NWC"6;
"S \NAC"
BN"7"44;
%"TAP"
"1","(-5825,4100)","2","mstr_standard","I277";
;
CDS_LIB"mstr_standard"
BODY_TYPE"PLUMBING"
HDL_TAP"TRUE";
"B \NAC \NWC"6;
"S \NAC"
BN"9"40;
%"TAP"
"1","(-6025,4550)","2","mstr_standard","I278";
;
CDS_LIB"mstr_standard"
BODY_TYPE"PLUMBING"
HDL_TAP"TRUE";
"B \NAC \NWC"10;
"S \NAC"
BN"4"56;
%"TAP"
"1","(-6025,4450)","2","mstr_standard","I279";
;
CDS_LIB"mstr_standard"
BODY_TYPE"PLUMBING"
HDL_TAP"TRUE";
"B \NAC \NWC"10;
"S \NAC"
BN"5"54;
%"TAP"
"1","(-6025,4350)","2","mstr_standard","I280";
;
CDS_LIB"mstr_standard"
BODY_TYPE"PLUMBING"
HDL_TAP"TRUE";
"B \NAC \NWC"10;
"S \NAC"
BN"6"52;
%"TAP"
"1","(-6025,4250)","2","mstr_standard","I281";
;
CDS_LIB"mstr_standard"
BODY_TYPE"PLUMBING"
HDL_TAP"TRUE";
"B \NAC \NWC"10;
"S \NAC"
BN"7"50;
%"TAP"
"1","(-6025,4150)","2","mstr_standard","I282";
;
CDS_LIB"mstr_standard"
BODY_TYPE"PLUMBING"
HDL_TAP"TRUE";
"B \NAC \NWC"10;
"S \NAC"
BN"8"48;
%"TAP"
"1","(-6025,4050)","2","mstr_standard","I287";
;
CDS_LIB"mstr_standard"
BODY_TYPE"PLUMBING"
HDL_TAP"TRUE";
"B \NAC \NWC"10;
"S \NAC"
BN"9"36;
%"TAP"
"1","(-6025,3900)","2","mstr_standard","I288";
;
CDS_LIB"mstr_standard"
BODY_TYPE"PLUMBING"
HDL_TAP"TRUE";
"B \NAC \NWC"7;
"S \NAC"
BN"0"39;
%"TAP"
"1","(-6025,3850)","2","mstr_standard","I289";
;
CDS_LIB"mstr_standard"
BODY_TYPE"PLUMBING"
HDL_TAP"TRUE";
"B \NAC \NWC"7;
"S \NAC"
BN"1"37;
%"TAP"
"1","(-6025,3800)","2","mstr_standard","I290";
;
CDS_LIB"mstr_standard"
BODY_TYPE"PLUMBING"
HDL_TAP"TRUE";
"B \NAC \NWC"7;
"S \NAC"
BN"2"34;
%"TAP"
"1","(-6025,3750)","2","mstr_standard","I291";
;
CDS_LIB"mstr_standard"
BODY_TYPE"PLUMBING"
HDL_TAP"TRUE";
"B \NAC \NWC"7;
"S \NAC"
BN"3"32;
%"TAP"
"1","(-6025,3600)","2","mstr_standard","I292";
;
CDS_LIB"mstr_standard"
BODY_TYPE"PLUMBING"
HDL_TAP"TRUE";
"B \NAC \NWC"7;
"S \NAC"
BN"6"26;
%"TAP"
"1","(-6025,3650)","2","mstr_standard","I293";
;
CDS_LIB"mstr_standard"
BODY_TYPE"PLUMBING"
HDL_TAP"TRUE";
"B \NAC \NWC"7;
"S \NAC"
BN"5"28;
%"TAP"
"1","(-6025,3700)","2","mstr_standard","I294";
;
CDS_LIB"mstr_standard"
BODY_TYPE"PLUMBING"
HDL_TAP"TRUE";
"B \NAC \NWC"7;
"S \NAC"
BN"4"30;
%"TAP"
"1","(-6025,3500)","2","mstr_standard","I295";
;
CDS_LIB"mstr_standard"
BODY_TYPE"PLUMBING"
HDL_TAP"TRUE";
"B \NAC \NWC"8;
"S \NAC"
BN"0"38;
%"TAP"
"1","(-6025,3450)","2","mstr_standard","I296";
;
CDS_LIB"mstr_standard"
BODY_TYPE"PLUMBING"
HDL_TAP"TRUE";
"B \NAC \NWC"8;
"S \NAC"
BN"1"35;
%"TAP"
"1","(-6025,3350)","2","mstr_standard","I297";
;
CDS_LIB"mstr_standard"
BODY_TYPE"PLUMBING"
HDL_TAP"TRUE";
"B \NAC \NWC"8;
"S \NAC"
BN"3"31;
%"TAP"
"1","(-6025,3400)","2","mstr_standard","I298";
;
CDS_LIB"mstr_standard"
BODY_TYPE"PLUMBING"
HDL_TAP"TRUE";
"B \NAC \NWC"8;
"S \NAC"
BN"2"33;
%"TAP"
"1","(-6025,3300)","2","mstr_standard","I299";
;
CDS_LIB"mstr_standard"
BODY_TYPE"PLUMBING"
HDL_TAP"TRUE";
"B \NAC \NWC"8;
"S \NAC"
BN"4"29;
%"TAP"
"1","(-6025,3250)","2","mstr_standard","I300";
;
CDS_LIB"mstr_standard"
BODY_TYPE"PLUMBING"
HDL_TAP"TRUE";
"B \NAC \NWC"8;
"S \NAC"
BN"5"27;
%"TAP"
"1","(-6025,3200)","2","mstr_standard","I301";
;
CDS_LIB"mstr_standard"
BODY_TYPE"PLUMBING"
HDL_TAP"TRUE";
"B \NAC \NWC"8;
"S \NAC"
BN"6"25;
%"Q_RES"
"1","(-6950,2200)","0","pure_quanta","I315";
;
LOCATION"R379"
$SEC"1"
CDS_SEC"1"
TOLERANCE"1%"
VALUE"15   "
PART_NUMBER"CS01502FB11"
PACK_TYPE"0402LF"
CDS_LIB"pure_quanta"
WATTAGE"1/16W"
MATERIAL"CHIP";
"B"
$PN"2"13;
"A"
$PN"1"11;
END.
